(kicad_pcb
	(version 20260206)
	(generator "pcbnew")
	(generator_version "10.0")
	(general
		(thickness 1.6)
		(legacy_teardrops no)
	)
	(paper "A4")
	(title_block
		(title "03242023_DA0F0TMBIJ0_F0T_Motherboard_J_brd_V01_OCP.brd")
		(comment 1 "Grand Teton / footprint 1682 of 6105 (U1), pads 855-956 of 4677")
	)
	(layers
		(0 "F.Cu" signal "TOP")
		(4 "In1.Cu" signal "GND")
		(6 "In2.Cu" signal "IN1")
		(8 "In3.Cu" signal "GND1")
		(10 "In4.Cu" signal "IN2")
		(12 "In5.Cu" signal "GND2")
		(14 "In6.Cu" signal "IN3")
		(16 "In7.Cu" signal "GND3")
		(18 "In8.Cu" signal "VCC")
		(20 "In9.Cu" signal "VCC1")
		(22 "In10.Cu" signal "GND4")
		(24 "In11.Cu" signal "IN4")
		(26 "In12.Cu" signal "GND5")
		(28 "In13.Cu" signal "IN5")
		(30 "In14.Cu" signal "GND6")
		(32 "In15.Cu" signal "IN6")
		(34 "In16.Cu" signal "GND7")
		(2 "B.Cu" signal "BOTTOM")
		(9 "F.Adhes" user "F.Adhesive")
		(11 "B.Adhes" user "B.Adhesive")
		(13 "F.Paste" user "Package Geometry/Pastemask Top")
		(15 "B.Paste" user "Package Geometry/Pastemask Bottom")
		(5 "F.SilkS" user "Ref Des/Silkscreen Top")
		(7 "B.SilkS" user "Ref Des/Silkscreen Bottom")
		(1 "F.Mask" user "Board Geometry/Soldermask Top")
		(3 "B.Mask" user "Board Geometry/Soldermask Bottom")
		(17 "Dwgs.User" user "User.Drawings")
		(19 "Cmts.User" user "User.Comments")
		(21 "Eco1.User" user "User.Eco1")
		(23 "Eco2.User" user "User.Eco2")
		(25 "Edge.Cuts" user "Board Geometry/Outline")
		(27 "Margin" user)
		(31 "F.CrtYd" user "Package Geometry/Place Bound Top")
		(29 "B.CrtYd" user "Package Geometry/Place Bound Bottom")
		(35 "F.Fab" user "Ref Des/Assembly Top")
		(33 "B.Fab" user "Ref Des/Assembly Bottom")
	)
	(footprint ""
		(layer "F.Cu")
		(at 111.93018 -251.76988 90)
		(property "Reference" "U1"
			(at -74.913236 41.548812 0)
			(unlocked yes)
			(layer "F.SilkS")
			(effects
				(font
					(size 1.6002 1.1938)
					(thickness 0.1524)
				)
				(justify left)
			)
		)
		(property "Value" ""
			(at 0 0 90)
			(layer "F.Fab")
			(effects
				(font
					(size 1.27 1.27)
				)
			)
		)
		(duplicate_pad_numbers_are_jumpers no)
		(pad "AW70" smd circle
			(at 20.333462 -9.107932 270)
			(size 0.4318 0.4318)
			(layers "F.Cu" "F.Mask" "F.Paste")
			(net "FM_S3M_CPU1_LVC1_GPIO_4")
		)
		(pad "AW72" smd circle
			(at 21.961094 -9.107932 270)
			(size 0.4318 0.4318)
			(layers "F.Cu" "F.Mask" "F.Paste")
			(net "GND")
		)
		(pad "AW74" smd circle
			(at 23.58898 -9.107932 270)
			(size 0.4318 0.4318)
			(layers "F.Cu" "F.Mask" "F.Paste")
			(net "UPI_CPU0_CPU1_P2P2_DN<16>")
		)
		(pad "AW76" smd circle
			(at 25.216612 -9.107932 270)
			(size 0.4318 0.4318)
			(layers "F.Cu" "F.Mask" "F.Paste")
			(net "PVCCFA_EHV_FIVRA_CPU1")
		)
		(pad "AW78" smd circle
			(at 26.844498 -9.107932 270)
			(size 0.4318 0.4318)
			(layers "F.Cu" "F.Mask" "F.Paste")
			(net "UPI_CPU1_CPU0_P2P2_DN<10>")
		)
		(pad "AW80" smd circle
			(at 28.472384 -9.107932 270)
			(size 0.4318 0.4318)
			(layers "F.Cu" "F.Mask" "F.Paste")
			(net "GND")
		)
		(pad "AW82" smd circle
			(at 30.100016 -9.107932 270)
			(size 0.4318 0.4318)
			(layers "F.Cu" "F.Mask" "F.Paste")
			(net "GND")
		)
		(pad "AW84" smd circle
			(at 31.727902 -9.107932 270)
			(size 0.4318 0.4318)
			(layers "F.Cu" "F.Mask" "F.Paste")
			(net "GND")
		)
		(pad "AW86" smd circle
			(at 33.355534 -9.107932 270)
			(size 0.4318 0.4318)
			(layers "F.Cu" "F.Mask" "F.Paste")
			(net "P5E_CPU1_PE4_TX_DN<14>")
		)
		(pad "AW88" smd circle
			(at 34.98342 -9.107932 270)
			(size 0.4318 0.4318)
			(layers "F.Cu" "F.Mask" "F.Paste")
			(net "GND")
		)
		(pad "AW90" smd circle
			(at 36.611306 -9.107932 270)
			(size 0.4318 0.4318)
			(layers "F.Cu" "F.Mask" "F.Paste")
			(net "P5E_CPU1_PE4_RX_DP<14>")
		)
		(pad "AY2" smd circle
			(at -36.611306 -8.748268 270)
			(size 0.4318 0.4318)
			(layers "F.Cu" "F.Mask" "F.Paste")
			(net "UPI_CPU1_CPU0_P0P1_DN<15>")
		)
		(pad "AY4" smd circle
			(at -34.98342 -8.748268 270)
			(size 0.4318 0.4318)
			(layers "F.Cu" "F.Mask" "F.Paste")
			(net "GND")
		)
		(pad "AY6" smd circle
			(at -33.355534 -8.748268 270)
			(size 0.4318 0.4318)
			(layers "F.Cu" "F.Mask" "F.Paste")
			(net "UPI_CPU0_CPU1_P1P0_DP<15>")
		)
		(pad "AY8" smd circle
			(at -31.727902 -8.748268 270)
			(size 0.4318 0.4318)
			(layers "F.Cu" "F.Mask" "F.Paste")
			(net "GND")
		)
		(pad "AY10" smd circle
			(at -30.100016 -8.748268 270)
			(size 0.4318 0.4318)
			(layers "F.Cu" "F.Mask" "F.Paste")
			(net "P5E_CPU1_PE0_RX_DP<15>")
		)
		(pad "AY12" smd circle
			(at -28.472384 -8.748268 270)
			(size 0.4318 0.4318)
			(layers "F.Cu" "F.Mask" "F.Paste")
			(net "GND")
		)
		(pad "AY14" smd circle
			(at -26.844498 -8.748268 270)
			(size 0.4318 0.4318)
			(layers "F.Cu" "F.Mask" "F.Paste")
			(net "P5E_CPU1_PE0_TX_DP<14>")
		)
		(pad "AY16" smd circle
			(at -25.216612 -8.748268 270)
			(size 0.4318 0.4318)
			(layers "F.Cu" "F.Mask" "F.Paste")
			(net "GND")
		)
		(pad "AY18" smd circle
			(at -23.58898 -8.748268 270)
			(size 0.4318 0.4318)
			(layers "F.Cu" "F.Mask" "F.Paste")
			(net "PVCCINFAON_CPU1")
		)
		(pad "AY20" smd circle
			(at -21.961094 -8.748268 270)
			(size 0.4318 0.4318)
			(layers "F.Cu" "F.Mask" "F.Paste")
			(net "PU_TAP_ODT_CPU1_EN")
		)
		(pad "AY22" smd circle
			(at -20.333462 -8.748268 270)
			(size 0.4318 0.4318)
			(layers "F.Cu" "F.Mask" "F.Paste")
			(net "H_CPU1_ERR1_LVC1_R_N")
		)
		(pad "AY24" smd circle
			(at -18.705576 -8.748268 270)
			(size 0.4318 0.4318)
			(layers "F.Cu" "F.Mask" "F.Paste")
			(net "NC_CPU1_SOC_SPARE0")
		)
		(pad "AY26" smd circle
			(at -17.07769 -8.748268 270)
			(size 0.4318 0.4318)
			(layers "F.Cu" "F.Mask" "F.Paste")
			(net "CPU1_RSVD<25>")
		)
		(pad "AY61" smd circle
			(at 13.008356 -8.638286 270)
			(size 0.4318 0.4318)
			(layers "F.Cu" "F.Mask" "F.Paste")
			(net "NC_SPI_CPU1_NCM_IO1")
		)
		(pad "AY63" smd circle
			(at 14.635988 -8.638286 270)
			(size 0.4318 0.4318)
			(layers "F.Cu" "F.Mask" "F.Paste")
			(net "FM_CPU1_PKGID1")
		)
		(pad "AY65" smd circle
			(at 16.263874 -8.638286 270)
			(size 0.4318 0.4318)
			(layers "F.Cu" "F.Mask" "F.Paste")
			(net "CPU1_RSVD<27>")
		)
		(pad "AY67" smd circle
			(at 17.89176 -8.638286 270)
			(size 0.4318 0.4318)
			(layers "F.Cu" "F.Mask" "F.Paste")
			(net "NC_SPI_CPU1_NCM_CS0_N")
		)
		(pad "AY69" smd circle
			(at 19.519392 -8.638286 270)
			(size 0.4318 0.4318)
			(layers "F.Cu" "F.Mask" "F.Paste")
			(net "FM_S3M_CPU1_LVC1_GPIO_3")
		)
		(pad "AY71" smd circle
			(at 21.147278 -8.638286 270)
			(size 0.4318 0.4318)
			(layers "F.Cu" "F.Mask" "F.Paste")
			(net "GND")
		)
		(pad "AY73" smd circle
			(at 22.77491 -8.638286 270)
			(size 0.4318 0.4318)
			(layers "F.Cu" "F.Mask" "F.Paste")
			(net "UPI_CPU0_CPU1_P2P2_DP<13>")
		)
		(pad "AY75" smd circle
			(at 24.402796 -8.638286 270)
			(size 0.4318 0.4318)
			(layers "F.Cu" "F.Mask" "F.Paste")
			(net "UPI_CPU0_CPU1_P2P2_DN<14>")
		)
		(pad "AY77" smd circle
			(at 26.030682 -8.638286 270)
			(size 0.4318 0.4318)
			(layers "F.Cu" "F.Mask" "F.Paste")
			(net "GND")
		)
		(pad "AY79" smd circle
			(at 27.658314 -8.638286 270)
			(size 0.4318 0.4318)
			(layers "F.Cu" "F.Mask" "F.Paste")
			(net "GND")
		)
		(pad "AY81" smd circle
			(at 29.2862 -8.638286 270)
			(size 0.4318 0.4318)
			(layers "F.Cu" "F.Mask" "F.Paste")
			(net "GND")
		)
		(pad "AY83" smd circle
			(at 30.914086 -8.638286 270)
			(size 0.4318 0.4318)
			(layers "F.Cu" "F.Mask" "F.Paste")
			(net "GND")
		)
		(pad "AY85" smd circle
			(at 32.541718 -8.638286 270)
			(size 0.4318 0.4318)
			(layers "F.Cu" "F.Mask" "F.Paste")
			(net "VSENSE_PVCCFA_EHV_FIVRA_CPU1_DP")
		)
		(pad "AY87" smd circle
			(at 34.169604 -8.638286 270)
			(size 0.4318 0.4318)
			(layers "F.Cu" "F.Mask" "F.Paste")
			(net "P5E_CPU1_PE4_TX_DP<14>")
		)
		(pad "AY89" smd circle
			(at 35.797236 -8.638286 270)
			(size 0.4318 0.4318)
			(layers "F.Cu" "F.Mask" "F.Paste")
			(net "PVCCFA_EHV_FIVRA_CPU1")
		)
		(pad "AY91" smd oval
			(at 37.425122 -8.638286)
			(size 0.381 0.4826)
			(drill
				(offset 0 -0.0508)
			)
			(layers "F.Cu" "F.Mask" "F.Paste")
			(net "P5E_CPU1_PE4_RX_DN<14>")
		)
		(pad "B6" smd oval
			(at -33.355534 -26.604468 135)
			(size 0.381 0.4826)
			(drill
				(offset 0 -0.0508)
			)
			(layers "F.Cu" "F.Mask" "F.Paste")
			(net "GND")
		)
		(pad "B8" smd oval
			(at -31.727902 -26.604468 135)
			(size 0.381 0.4826)
			(drill
				(offset 0 -0.0508)
			)
			(layers "F.Cu" "F.Mask" "F.Paste")
			(net "M_A_CPU1_SB_DQ<28>")
		)
		(pad "B10" smd oval
			(at -30.100016 -26.604468 90)
			(size 0.381 0.4826)
			(drill
				(offset 0 -0.0508)
			)
			(layers "F.Cu" "F.Mask" "F.Paste")
			(net "M_A_CPU1_SB_DQ<25>")
		)
		(pad "B12" smd circle
			(at -28.472384 -26.604468 270)
			(size 0.4318 0.4318)
			(layers "F.Cu" "F.Mask" "F.Paste")
			(net "GND")
		)
		(pad "B14" smd circle
			(at -26.844498 -26.604468 270)
			(size 0.4318 0.4318)
			(layers "F.Cu" "F.Mask" "F.Paste")
			(net "M_B_CPU1_SB_DQ<30>")
		)
		(pad "B16" smd circle
			(at -25.216612 -26.604468 270)
			(size 0.4318 0.4318)
			(layers "F.Cu" "F.Mask" "F.Paste")
			(net "M_B_CPU1_SB_DQ<25>")
		)
		(pad "B18" smd circle
			(at -23.58898 -26.604468 270)
			(size 0.4318 0.4318)
			(layers "F.Cu" "F.Mask" "F.Paste")
			(net "GND")
		)
		(pad "B20" smd circle
			(at -21.961094 -26.604468 270)
			(size 0.4318 0.4318)
			(layers "F.Cu" "F.Mask" "F.Paste")
			(net "M_A_CPU1_SB_DQ<20>")
		)
		(pad "B22" smd circle
			(at -20.333462 -26.604468 270)
			(size 0.4318 0.4318)
			(layers "F.Cu" "F.Mask" "F.Paste")
			(net "M_A_CPU1_SB_DQ<17>")
		)
		(pad "B24" smd circle
			(at -18.705576 -26.604468 270)
			(size 0.4318 0.4318)
			(layers "F.Cu" "F.Mask" "F.Paste")
			(net "GND")
		)
		(pad "B26" smd circle
			(at -17.07769 -26.604468 270)
			(size 0.4318 0.4318)
			(layers "F.Cu" "F.Mask" "F.Paste")
			(net "M_A_CPU1_SB_DQ<12>")
		)
		(pad "B28" smd circle
			(at -15.450058 -26.604468 270)
			(size 0.4318 0.4318)
			(layers "F.Cu" "F.Mask" "F.Paste")
			(net "M_A_CPU1_SB_DQ<9>")
		)
		(pad "B30" smd circle
			(at -13.822426 -26.604468 270)
			(size 0.4318 0.4318)
			(layers "F.Cu" "F.Mask" "F.Paste")
			(net "GND")
		)
		(pad "B32" smd circle
			(at -12.19454 -26.604468 270)
			(size 0.4318 0.4318)
			(layers "F.Cu" "F.Mask" "F.Paste")
			(net "M_A_CPU1_SB_CB<0>")
		)
		(pad "B34" smd circle
			(at -10.566654 -26.604468 270)
			(size 0.4318 0.4318)
			(layers "F.Cu" "F.Mask" "F.Paste")
			(net "M_A_CPU1_SB_CB<5>")
		)
		(pad "B36" smd circle
			(at -8.939022 -26.604468 270)
			(size 0.4318 0.4318)
			(layers "F.Cu" "F.Mask" "F.Paste")
			(net "GND")
		)
		(pad "B38" smd circle
			(at -7.311136 -26.604468 270)
			(size 0.4318 0.4318)
			(layers "F.Cu" "F.Mask" "F.Paste")
			(net "M_A_CPU1_SB_CS_N<0>")
		)
		(pad "B40" smd circle
			(at -5.68325 -26.604468 270)
			(size 0.4318 0.4318)
			(layers "F.Cu" "F.Mask" "F.Paste")
			(net "M_A_CPU1_SB_CA<4>")
		)
		(pad "B42" smd circle
			(at -4.055618 -26.604468 270)
			(size 0.4318 0.4318)
			(layers "F.Cu" "F.Mask" "F.Paste")
			(net "GND")
		)
		(pad "B44" smd oval
			(at -2.427732 -26.604468 45)
			(size 0.381 0.4826)
			(drill
				(offset 0 -0.0508)
			)
			(layers "F.Cu" "F.Mask" "F.Paste")
			(net "M_A_CPU1_CLK_DN<0>")
		)
		(pad "B49" smd oval
			(at 3.241802 -26.494486 135)
			(size 0.381 0.4826)
			(drill
				(offset 0 -0.0508)
			)
			(layers "F.Cu" "F.Mask" "F.Paste")
			(net "GND")
		)
		(pad "B51" smd circle
			(at 4.869434 -26.494486 270)
			(size 0.4318 0.4318)
			(layers "F.Cu" "F.Mask" "F.Paste")
			(net "M_A_CPU1_SA_CA<2>")
		)
		(pad "B53" smd circle
			(at 6.49732 -26.494486 270)
			(size 0.4318 0.4318)
			(layers "F.Cu" "F.Mask" "F.Paste")
			(net "M_A_CPU1_SA_CS_N<1>")
		)
		(pad "B55" smd circle
			(at 8.124952 -26.494486 270)
			(size 0.4318 0.4318)
			(layers "F.Cu" "F.Mask" "F.Paste")
			(net "GND")
		)
		(pad "B57" smd circle
			(at 9.752838 -26.494486 270)
			(size 0.4318 0.4318)
			(layers "F.Cu" "F.Mask" "F.Paste")
			(net "M_A_CPU1_SA_CB<4>")
		)
		(pad "B59" smd circle
			(at 11.380724 -26.494486 270)
			(size 0.4318 0.4318)
			(layers "F.Cu" "F.Mask" "F.Paste")
			(net "M_A_CPU1_SA_CB<1>")
		)
		(pad "B61" smd circle
			(at 13.008356 -26.494486 270)
			(size 0.4318 0.4318)
			(layers "F.Cu" "F.Mask" "F.Paste")
			(net "GND")
		)
		(pad "B63" smd circle
			(at 14.635988 -26.494486 270)
			(size 0.4318 0.4318)
			(layers "F.Cu" "F.Mask" "F.Paste")
			(net "M_A_CPU1_SA_DQ<28>")
		)
		(pad "B65" smd oval
			(at 16.263874 -26.494486 90)
			(size 0.381 0.4826)
			(drill
				(offset 0 -0.0508)
			)
			(layers "F.Cu" "F.Mask" "F.Paste")
			(net "M_A_CPU1_SA_DQ<25>")
		)
		(pad "B67" smd oval
			(at 17.89176 -26.494486 90)
			(size 0.381 0.4826)
			(drill
				(offset 0 -0.0508)
			)
			(layers "F.Cu" "F.Mask" "F.Paste")
			(net "GND")
		)
		(pad "B69" smd oval
			(at 19.519392 -26.494486 90)
			(size 0.381 0.4826)
			(drill
				(offset 0 -0.0508)
			)
			(layers "F.Cu" "F.Mask" "F.Paste")
			(net "M_A_CPU1_SA_DQ<20>")
		)
		(pad "B71" smd oval
			(at 21.147278 -26.494486 90)
			(size 0.381 0.4826)
			(drill
				(offset 0 -0.0508)
			)
			(layers "F.Cu" "F.Mask" "F.Paste")
			(net "M_A_CPU1_SA_DQS_DN<2>")
		)
		(pad "B73" smd oval
			(at 22.77491 -26.494486 90)
			(size 0.381 0.4826)
			(drill
				(offset 0 -0.0508)
			)
			(layers "F.Cu" "F.Mask" "F.Paste")
			(net "M_A_CPU1_SA_DQ<16>")
		)
		(pad "B75" smd oval
			(at 24.402796 -26.494486 90)
			(size 0.381 0.4826)
			(drill
				(offset 0 -0.0508)
			)
			(layers "F.Cu" "F.Mask" "F.Paste")
			(net "GND")
		)
		(pad "B77" smd oval
			(at 26.030682 -26.494486 90)
			(size 0.381 0.4826)
			(drill
				(offset 0 -0.0508)
			)
			(layers "F.Cu" "F.Mask" "F.Paste")
			(net "M_A_CPU1_SA_DQS_DN<0>")
		)
		(pad "B79" smd oval
			(at 27.658314 -26.494486 90)
			(size 0.381 0.4826)
			(drill
				(offset 0 -0.0508)
			)
			(layers "F.Cu" "F.Mask" "F.Paste")
			(net "M_A_CPU1_SA_DQ<1>")
		)
		(pad "B81" smd oval
			(at 29.2862 -26.494486 90)
			(size 0.381 0.4826)
			(drill
				(offset 0 -0.0508)
			)
			(layers "F.Cu" "F.Mask" "F.Paste")
			(net "M_A_CPU1_SA_DQ<0>")
		)
		(pad "B83" smd oval
			(at 30.914086 -26.494486 45)
			(size 0.381 0.4826)
			(drill
				(offset 0 -0.0508)
			)
			(layers "F.Cu" "F.Mask" "F.Paste")
			(net "GND")
		)
		(pad "B85" smd oval
			(at 32.541718 -26.494486 45)
			(size 0.381 0.4826)
			(drill
				(offset 0 -0.0508)
			)
			(layers "F.Cu" "F.Mask" "F.Paste")
			(net "UPI_CPU1_CPU0_P2P2_DN<0>")
		)
		(pad "B87" smd oval
			(at 34.169604 -26.494486 45)
			(size 0.381 0.4826)
			(drill
				(offset 0 -0.0508)
			)
			(layers "F.Cu" "F.Mask" "F.Paste")
			(net "GND")
		)
		(pad "BA1" smd oval
			(at -37.425122 -8.278114 180)
			(size 0.381 0.4826)
			(drill
				(offset 0 -0.0508)
			)
			(layers "F.Cu" "F.Mask" "F.Paste")
			(net "UPI_CPU1_CPU0_P0P1_DP<16>")
		)
		(pad "BA3" smd circle
			(at -35.797236 -8.278114 270)
			(size 0.4318 0.4318)
			(layers "F.Cu" "F.Mask" "F.Paste")
			(net "PVCCD_HV_CPU1")
		)
		(pad "BA5" smd circle
			(at -34.169604 -8.278114 270)
			(size 0.4318 0.4318)
			(layers "F.Cu" "F.Mask" "F.Paste")
			(net "UPI_CPU0_CPU1_P1P0_DN<15>")
		)
		(pad "BA7" smd circle
			(at -32.541718 -8.278114 270)
			(size 0.4318 0.4318)
			(layers "F.Cu" "F.Mask" "F.Paste")
			(net "PVCCD_HV_CPU1")
		)
		(pad "BA9" smd circle
			(at -30.914086 -8.278114 270)
			(size 0.4318 0.4318)
			(layers "F.Cu" "F.Mask" "F.Paste")
			(net "P5E_CPU1_PE0_RX_DN<15>")
		)
		(pad "BA11" smd circle
			(at -29.2862 -8.278114 270)
			(size 0.4318 0.4318)
			(layers "F.Cu" "F.Mask" "F.Paste")
			(net "VSENSE_PVCCFA_EHV_CPU1_DN")
		)
		(pad "BA13" smd circle
			(at -27.658314 -8.278114 270)
			(size 0.4318 0.4318)
			(layers "F.Cu" "F.Mask" "F.Paste")
			(net "P5E_CPU1_PE0_TX_DN<14>")
		)
		(pad "BA15" smd circle
			(at -26.030682 -8.278114 270)
			(size 0.4318 0.4318)
			(layers "F.Cu" "F.Mask" "F.Paste")
			(net "PVCCINFAON_CPU1")
		)
		(pad "BA17" smd circle
			(at -24.402796 -8.278114 270)
			(size 0.4318 0.4318)
			(layers "F.Cu" "F.Mask" "F.Paste")
			(net "GND")
		)
		(pad "BA19" smd circle
			(at -22.77491 -8.278114 270)
			(size 0.4318 0.4318)
			(layers "F.Cu" "F.Mask" "F.Paste")
			(net "PVNN_MAIN_CPU1")
		)
		(pad "BA21" smd circle
			(at -21.147278 -8.278114 270)
			(size 0.4318 0.4318)
			(layers "F.Cu" "F.Mask" "F.Paste")
			(net "P3V3_AUX")
		)
		(pad "BA23" smd circle
			(at -19.519392 -8.278114 270)
			(size 0.4318 0.4318)
			(layers "F.Cu" "F.Mask" "F.Paste")
			(net "PU_CPU1_UPI0_AC_COUPLING")
		)
		(pad "BA25" smd circle
			(at -17.89176 -8.278114 270)
			(size 0.4318 0.4318)
			(layers "F.Cu" "F.Mask" "F.Paste")
			(net "NC_CPU1_SOC_SPARE4")
		)
		(pad "BA60" smd circle
			(at 12.19454 -8.168132 270)
			(size 0.4318 0.4318)
			(layers "F.Cu" "F.Mask" "F.Paste")
			(net "GND")
		)
		(pad "BA62" smd circle
			(at 13.822426 -8.168132 270)
			(size 0.4318 0.4318)
			(layers "F.Cu" "F.Mask" "F.Paste")
			(net "NC_SPI_S3M_CPU1_IO0_LVC1_R")
		)
		(pad "BA64" smd circle
			(at 15.450058 -8.168132 270)
			(size 0.4318 0.4318)
			(layers "F.Cu" "F.Mask" "F.Paste")
			(net "GND")
		)
		(pad "BA66" smd circle
			(at 17.07769 -8.168132 270)
			(size 0.4318 0.4318)
			(layers "F.Cu" "F.Mask" "F.Paste")
			(net "NC_SPI_CPU1_NCM_IO0")
		)
		(pad "BA68" smd circle
			(at 18.705576 -8.168132 270)
			(size 0.4318 0.4318)
			(layers "F.Cu" "F.Mask" "F.Paste")
			(net "NC_SPI_S3M_CPU1_OE_LVC1_R_N")
		)
		(pad "BA70" smd circle
			(at 20.333462 -8.168132 270)
			(size 0.4318 0.4318)
			(layers "F.Cu" "F.Mask" "F.Paste")
			(net "FM_S3M_CPU1_LVC1_GPIO_0")
		)
		(pad "BA72" smd circle
			(at 21.961094 -8.168132 270)
			(size 0.4318 0.4318)
			(layers "F.Cu" "F.Mask" "F.Paste")
			(net "UPI_CPU0_CPU1_P2P2_DN<12>")
		)
		(pad "BA74" smd circle
			(at 23.58898 -8.168132 270)
			(size 0.4318 0.4318)
			(layers "F.Cu" "F.Mask" "F.Paste")
			(net "GND")
		)
		(pad "BA76" smd circle
			(at 25.216612 -8.168132 270)
			(size 0.4318 0.4318)
			(layers "F.Cu" "F.Mask" "F.Paste")
			(net "UPI_CPU0_CPU1_P2P2_DP<14>")
		)
	)
)
